# T6G (Grand Teton) — schematic netlist excerpt (pin names and nets, part order shuffled) for the footprints in the layout excerpt that follows; sources: Cadence DE-HDL packaged netlist, KiCad conversion of 04192023_DAF0TMB3IC0_F0TG_MB_C_brd_V02_OCP.brd

R3048  Q_RES  0 5% CHIP  pkg 0402LF  page 253 : A = MB0_P12V_STBY_PWRGD ; B = PWRGD_PS_PWROK
R723  Q_RES  4.7K 5% CHIP  pkg 0201LF  page 320 : A = TEST1_RT_CPU1_P0 ; B = GND
PR2537  Q_RES  10 1% EMPTY  pkg 0402LF  page 266 : A = P12V_AUX ; B = P12V_HSC_GATE_RC

(kicad_pcb
	(version 20260206)
	(generator "pcbnew")
	(generator_version "10.0")
	(general
		(thickness 1.6)
		(legacy_teardrops no)
	)
	(paper "A4")
	(title_block
		(title "04192023_DAF0TMB3IC0_F0TG_MB_C_brd_V02_OCP.brd")
		(comment 1 "Grand Teton / footprints 7932-7934 of 8354")
	)
	(layers
		(0 "F.Cu" signal "TOP")
		(4 "In1.Cu" signal "GND")
		(6 "In2.Cu" signal "IN1")
		(8 "In3.Cu" signal "GND1")
		(10 "In4.Cu" signal "IN2")
		(12 "In5.Cu" signal "GND2")
		(14 "In6.Cu" signal "IN3")
		(16 "In7.Cu" signal "GND3")
		(18 "In8.Cu" signal "VCC")
		(20 "In9.Cu" signal "VCC1")
		(22 "In10.Cu" signal "GND4")
		(24 "In11.Cu" signal "IN4")
		(26 "In12.Cu" signal "GND5")
		(28 "In13.Cu" signal "IN5")
		(30 "In14.Cu" signal "GND6")
		(32 "In15.Cu" signal "IN6")
		(34 "In16.Cu" signal "GND7")
		(2 "B.Cu" signal "BOTTOM")
		(9 "F.Adhes" user "F.Adhesive")
		(11 "B.Adhes" user "B.Adhesive")
		(13 "F.Paste" user "Package Geometry/Pastemask Top")
		(15 "B.Paste" user "Package Geometry/Pastemask Bottom")
		(5 "F.SilkS" user "Ref Des/Silkscreen Top")
		(7 "B.SilkS" user "Ref Des/Silkscreen Bottom")
		(1 "F.Mask" user "Board Geometry/Soldermask Top")
		(3 "B.Mask" user "Board Geometry/Soldermask Bottom")
		(17 "Dwgs.User" user "User.Drawings")
		(19 "Cmts.User" user "User.Comments")
		(21 "Eco1.User" user "User.Eco1")
		(23 "Eco2.User" user "User.Eco2")
		(25 "Edge.Cuts" user "Board Geometry/Outline")
		(27 "Margin" user)
		(31 "F.CrtYd" user "Package Geometry/Place Bound Top")
		(29 "B.CrtYd" user "Package Geometry/Place Bound Bottom")
		(35 "F.Fab" user "Ref Des/Assembly Top")
		(33 "B.Fab" user "Ref Des/Assembly Bottom")
	)
	(footprint ""
		(layer "B.Cu")
		(at 310.411876 -76.489814 -90)
		(property "Reference" "R3048"
			(at 0 0 90)
			(layer "B.SilkS")
			(hide yes)
			(effects
				(font
					(size 1.27 1.27)
				)
				(justify mirror)
			)
		)
		(property "Value" ""
			(at 0 0 90)
			(layer "B.Fab")
			(effects
				(font
					(size 1.27 1.27)
				)
				(justify mirror)
			)
		)
		(duplicate_pad_numbers_are_jumpers no)
		(fp_line
			(start -0.7874 0.4064)
			(end 0.7874 0.4064)
			(stroke
				(width 0.1524)
				(type default)
			)
			(layer "B.SilkS")
		)
		(fp_line
			(start 0.7874 0.4064)
			(end 0.7874 -0.4064)
			(stroke
				(width 0.1524)
				(type default)
			)
			(layer "B.SilkS")
		)
		(fp_line
			(start -0.7874 -0.4064)
			(end -0.7874 0.4064)
			(stroke
				(width 0.1524)
				(type default)
			)
			(layer "B.SilkS")
		)
		(fp_line
			(start 0.7874 -0.4064)
			(end -0.7874 -0.4064)
			(stroke
				(width 0.1524)
				(type default)
			)
			(layer "B.SilkS")
		)
		(fp_line
			(start -0.67945 0.3048)
			(end -0.120396 0.3048)
			(stroke
				(width 0.1)
				(type default)
			)
			(layer "B.Fab")
		)
		(fp_line
			(start -0.120396 0.3048)
			(end -0.120396 0.2794)
			(stroke
				(width 0.1)
				(type default)
			)
			(layer "B.Fab")
		)
		(fp_line
			(start 0.12065 0.3048)
			(end 0.67945 0.3048)
			(stroke
				(width 0.1)
				(type default)
			)
			(layer "B.Fab")
		)
		(fp_line
			(start 0.67945 0.3048)
			(end 0.67945 -0.305054)
			(stroke
				(width 0.1)
				(type default)
			)
			(layer "B.Fab")
		)
		(fp_line
			(start -0.120396 0.2794)
			(end 0.12065 0.2794)
			(stroke
				(width 0.1)
				(type default)
			)
			(layer "B.Fab")
		)
		(fp_line
			(start 0.12065 0.2794)
			(end 0.12065 0.3048)
			(stroke
				(width 0.1)
				(type default)
			)
			(layer "B.Fab")
		)
		(fp_line
			(start -0.12065 -0.2794)
			(end -0.12065 -0.3048)
			(stroke
				(width 0.1)
				(type default)
			)
			(layer "B.Fab")
		)
		(fp_line
			(start 0.12065 -0.2794)
			(end -0.12065 -0.2794)
			(stroke
				(width 0.1)
				(type default)
			)
			(layer "B.Fab")
		)
		(fp_line
			(start -0.67945 -0.3048)
			(end -0.67945 0.3048)
			(stroke
				(width 0.1)
				(type default)
			)
			(layer "B.Fab")
		)
		(fp_line
			(start -0.12065 -0.3048)
			(end -0.67945 -0.3048)
			(stroke
				(width 0.1)
				(type default)
			)
			(layer "B.Fab")
		)
		(fp_line
			(start 0.12065 -0.305054)
			(end 0.12065 -0.2794)
			(stroke
				(width 0.1)
				(type default)
			)
			(layer "B.Fab")
		)
		(fp_line
			(start 0.67945 -0.305054)
			(end 0.12065 -0.305054)
			(stroke
				(width 0.1)
				(type default)
			)
			(layer "B.Fab")
		)
		(pad "1" smd circle
			(at 0.40005 0 90)
			(size 0 0)
			(layers "B.Cu" "B.Mask" "B.Paste")
			(net "MB0_P12V_STBY_PWRGD")
		)
		(pad "2" smd circle
			(at -0.40005 0 90)
			(size 0 0)
			(layers "B.Cu" "B.Mask" "B.Paste")
			(net "PWRGD_PS_PWROK")
		)
	)
	(footprint ""
		(layer "B.Cu")
		(at 242.702842 -383.483358 180)
		(property "Reference" "PR2537"
			(at 0 0 0)
			(layer "B.SilkS")
			(hide yes)
			(effects
				(font
					(size 1.27 1.27)
				)
				(justify mirror)
			)
		)
		(property "Value" ""
			(at 0 0 0)
			(layer "B.Fab")
			(effects
				(font
					(size 1.27 1.27)
				)
				(justify mirror)
			)
		)
		(duplicate_pad_numbers_are_jumpers no)
		(fp_line
			(start 0.7874 0.4064)
			(end 0.7874 -0.4064)
			(stroke
				(width 0.1524)
				(type default)
			)
			(layer "B.SilkS")
		)
		(fp_line
			(start 0.7874 -0.4064)
			(end -0.7874 -0.4064)
			(stroke
				(width 0.1524)
				(type default)
			)
			(layer "B.SilkS")
		)
		(fp_line
			(start -0.7874 0.4064)
			(end 0.7874 0.4064)
			(stroke
				(width 0.1524)
				(type default)
			)
			(layer "B.SilkS")
		)
		(fp_line
			(start -0.7874 -0.4064)
			(end -0.7874 0.4064)
			(stroke
				(width 0.1524)
				(type default)
			)
			(layer "B.SilkS")
		)
		(fp_line
			(start 0.67945 0.3048)
			(end 0.67945 -0.305054)
			(stroke
				(width 0.1)
				(type default)
			)
			(layer "B.Fab")
		)
		(fp_line
			(start 0.67945 -0.305054)
			(end 0.12065 -0.305054)
			(stroke
				(width 0.1)
				(type default)
			)
			(layer "B.Fab")
		)
		(fp_line
			(start 0.12065 0.3048)
			(end 0.67945 0.3048)
			(stroke
				(width 0.1)
				(type default)
			)
			(layer "B.Fab")
		)
		(fp_line
			(start 0.12065 0.2794)
			(end 0.12065 0.3048)
			(stroke
				(width 0.1)
				(type default)
			)
			(layer "B.Fab")
		)
		(fp_line
			(start 0.12065 -0.2794)
			(end -0.12065 -0.2794)
			(stroke
				(width 0.1)
				(type default)
			)
			(layer "B.Fab")
		)
		(fp_line
			(start 0.12065 -0.305054)
			(end 0.12065 -0.2794)
			(stroke
				(width 0.1)
				(type default)
			)
			(layer "B.Fab")
		)
		(fp_line
			(start -0.120396 0.3048)
			(end -0.120396 0.2794)
			(stroke
				(width 0.1)
				(type default)
			)
			(layer "B.Fab")
		)
		(fp_line
			(start -0.120396 0.2794)
			(end 0.12065 0.2794)
			(stroke
				(width 0.1)
				(type default)
			)
			(layer "B.Fab")
		)
		(fp_line
			(start -0.12065 -0.2794)
			(end -0.12065 -0.3048)
			(stroke
				(width 0.1)
				(type default)
			)
			(layer "B.Fab")
		)
		(fp_line
			(start -0.12065 -0.3048)
			(end -0.67945 -0.3048)
			(stroke
				(width 0.1)
				(type default)
			)
			(layer "B.Fab")
		)
		(fp_line
			(start -0.67945 0.3048)
			(end -0.120396 0.3048)
			(stroke
				(width 0.1)
				(type default)
			)
			(layer "B.Fab")
		)
		(fp_line
			(start -0.67945 -0.3048)
			(end -0.67945 0.3048)
			(stroke
				(width 0.1)
				(type default)
			)
			(layer "B.Fab")
		)
		(pad "1" smd circle
			(at 0.40005 0)
			(size 0 0)
			(layers "B.Cu" "B.Mask" "B.Paste")
			(net "P12V_AUX")
		)
		(pad "2" smd circle
			(at -0.40005 0)
			(size 0 0)
			(layers "B.Cu" "B.Mask" "B.Paste")
			(net "P12V_HSC_GATE_RC")
		)
	)
	(footprint ""
		(layer "B.Cu")
		(at 43.265852 -384.28676 180)
		(property "Reference" "R723"
			(at 0 0 0)
			(layer "B.SilkS")
			(hide yes)
			(effects
				(font
					(size 1.27 1.27)
				)
				(justify mirror)
			)
		)
		(property "Value" ""
			(at 0 0 0)
			(layer "B.Fab")
			(effects
				(font
					(size 1.27 1.27)
				)
				(justify mirror)
			)
		)
		(duplicate_pad_numbers_are_jumpers no)
		(fp_line
			(start 0.32512 0.175006)
			(end 0.32512 -0.175006)
			(stroke
				(width 0.1)
				(type default)
			)
			(layer "B.Fab")
		)
		(fp_line
			(start 0.32512 -0.175006)
			(end -0.32512 -0.175006)
			(stroke
				(width 0.1)
				(type default)
			)
			(layer "B.Fab")
		)
		(fp_line
			(start -0.32512 0.175006)
			(end 0.32512 0.175006)
			(stroke
				(width 0.1)
				(type default)
			)
			(layer "B.Fab")
		)
		(fp_line
			(start -0.32512 -0.175006)
			(end -0.32512 0.175006)
			(stroke
				(width 0.1)
				(type default)
			)
			(layer "B.Fab")
		)
		(pad "1" smd rect
			(at 0.2667 0)
			(size 0.3048 0.381)
			(layers "B.Cu" "B.Mask" "B.Paste")
			(net "TEST1_RT_CPU1_P0")
		)
		(pad "2" smd rect
			(at -0.2667 0 180)
			(size 0.3048 0.381)
			(layers "B.Cu" "B.Mask" "B.Paste")
			(net "GND")
		)
	)
)
